(kicad_pcb
	(version 20260206)
	(generator "pcbnew")
	(generator_version "10.0")
	(general
		(thickness 1.6)
		(legacy_teardrops no)
	)
	(paper "A4")
	(title_block
		(title "baseboard — 13948-1b.1110WZS1818.brd")
		(comment 1 "Honey Badger (Wiwynn) / footprints 1808-1816 of 2523")
	)
	(layers
		(0 "F.Cu" signal "TOP")
		(4 "In1.Cu" signal "L2GND")
		(6 "In2.Cu" signal "L3")
		(8 "In3.Cu" signal "L4VCC")
		(10 "In4.Cu" signal "L5VCC")
		(12 "In5.Cu" signal "L6")
		(14 "In6.Cu" signal "L7GND")
		(2 "B.Cu" signal "BOTTOM")
		(9 "F.Adhes" user "F.Adhesive")
		(11 "B.Adhes" user "B.Adhesive")
		(13 "F.Paste" user "Package Geometry/Pastemask Top")
		(15 "B.Paste" user "Package Geometry/Pastemask Bottom")
		(5 "F.SilkS" user "Ref Des/Silkscreen Top")
		(7 "B.SilkS" user "Ref Des/Silkscreen Bottom")
		(1 "F.Mask" user "Board Geometry/Soldermask Top")
		(3 "B.Mask" user "Board Geometry/Soldermask Bottom")
		(17 "Dwgs.User" user "User.Drawings")
		(19 "Cmts.User" user "User.Comments")
		(21 "Eco1.User" user "User.Eco1")
		(23 "Eco2.User" user "User.Eco2")
		(25 "Edge.Cuts" user "Board Geometry/Outline")
		(27 "Margin" user)
		(31 "F.CrtYd" user "Package Geometry/Place Bound Top")
		(29 "B.CrtYd" user "Package Geometry/Place Bound Bottom")
		(35 "F.Fab" user "Ref Des/Assembly Top")
		(33 "B.Fab" user "Ref Des/Assembly Bottom")
	)
	(footprint ""
		(layer "B.Cu")
		(at 348.5642 -71.8058)
		(property "Reference" "R346"
			(at 0 0 0)
			(layer "B.SilkS")
			(hide yes)
			(effects
				(font
					(size 1.27 1.27)
				)
				(justify mirror)
			)
		)
		(property "Value" "3K3R2F-2-GP"
			(at -0.064008 -3.993896 0)
			(unlocked yes)
			(layer "B.Fab")
			(hide yes)
			(effects
				(font
					(size 1.016 1.016)
					(thickness 0.1524)
				)
				(justify mirror)
			)
		)
		(property "Device Type" "R402H16"
			(at -0.064008 -5.517896 0)
			(unlocked yes)
			(layer "B.Fab")
			(hide yes)
			(effects
				(font
					(size 1.016 1.016)
					(thickness 0.1524)
				)
				(justify mirror)
			)
		)
		(duplicate_pad_numbers_are_jumpers no)
		(fp_line
			(start -0.508 -0.9398)
			(end 0.508 -0.9398)
			(stroke
				(width 0.1524)
				(type default)
			)
			(layer "B.SilkS")
		)
		(fp_line
			(start 0.508 -0.9398)
			(end 0.508 0.9398)
			(stroke
				(width 0.1524)
				(type default)
			)
			(layer "B.SilkS")
		)
		(fp_rect
			(start 0.508 0.9398)
			(end -0.508 -0.9398)
			(stroke
				(width 0)
				(type default)
			)
			(fill no)
			(layer "B.CrtYd")
		)
		(fp_rect
			(start 0.508 0.9398)
			(end -0.508 -0.9398)
			(stroke
				(width 0)
				(type default)
			)
			(fill no)
			(layer "B.Fab")
		)
		(pad "1" smd custom
			(at 0 -0.4445 180)
			(size 0.1397 0.1397)
			(layers "B.Cu" "B.Mask" "B.Paste")
			(net "P3V3_STBY")
			(options
				(clearance outline)
				(anchor circle)
			)
			(primitives
				(gr_poly
					(pts
						(arc
							(start -0.1778 0.2794)
							(mid -0.249642 0.249642)
							(end -0.2794 0.1778)
						)
						(arc
							(start -0.2794 -0.1778)
							(mid -0.249642 -0.249642)
							(end -0.1778 -0.2794)
						)
						(arc
							(start 0.1778 -0.2794)
							(mid 0.249642 -0.249642)
							(end 0.2794 -0.1778)
						)
						(arc
							(start 0.2794 0.1778)
							(mid 0.249642 0.249642)
							(end 0.1778 0.2794)
						)
					)
					(width 0)
					(fill yes)
				)
			)
		)
		(pad "2" smd custom
			(at 0 0.4445 180)
			(size 0.1397 0.1397)
			(layers "B.Cu" "B.Mask" "B.Paste")
			(net "ROMD1_R")
			(options
				(clearance outline)
				(anchor circle)
			)
			(primitives
				(gr_poly
					(pts
						(arc
							(start -0.1778 0.2794)
							(mid -0.249642 0.249642)
							(end -0.2794 0.1778)
						)
						(arc
							(start -0.2794 -0.1778)
							(mid -0.249642 -0.249642)
							(end -0.1778 -0.2794)
						)
						(arc
							(start 0.1778 -0.2794)
							(mid 0.249642 -0.249642)
							(end 0.2794 -0.1778)
						)
						(arc
							(start 0.2794 0.1778)
							(mid 0.249642 0.249642)
							(end 0.1778 0.2794)
						)
					)
					(width 0)
					(fill yes)
				)
			)
		)
	)
	(footprint ""
		(layer "B.Cu")
		(at 295.5798 -181.4576)
		(property "Reference" "TP191"
			(at 0 0 0)
			(layer "B.SilkS")
			(hide yes)
			(effects
				(font
					(size 1.27 1.27)
				)
				(justify mirror)
			)
		)
		(property "Value" "TPAD28"
			(at 0.0127 -1.6637 0)
			(unlocked yes)
			(layer "B.Fab")
			(hide yes)
			(effects
				(font
					(size 1.016 1.016)
					(thickness 0.1524)
				)
				(justify mirror)
			)
		)
		(property "Device Type" "TPAD28"
			(at 0.0127 -3.1877 0)
			(unlocked yes)
			(layer "B.Fab")
			(hide yes)
			(effects
				(font
					(size 1.016 1.016)
					(thickness 0.1524)
				)
				(justify mirror)
			)
		)
		(duplicate_pad_numbers_are_jumpers no)
		(fp_poly
			(pts
				(arc
					(start 0.3556 0)
					(mid -0.3556 0)
					(end 0.3556 0)
				)
			)
			(stroke
				(width 0)
				(type default)
			)
			(fill no)
			(layer "B.CrtYd")
		)
		(fp_poly
			(pts
				(arc
					(start 0.6096 0)
					(mid -0.6096 0)
					(end 0.6096 0)
				)
			)
			(stroke
				(width 0)
				(type default)
			)
			(fill no)
			(layer "B.Fab")
		)
		(pad "1" smd circle
			(at 0 0 180)
			(size 0.7112 0.7112)
			(layers "B.Cu" "B.Mask" "B.Paste")
			(net "TP_BMC_GPIOO7")
		)
	)
	(footprint ""
		(layer "B.Cu")
		(at 108.020612 -204.978 180)
		(property "Reference" "SR899"
			(at 0 0 0)
			(layer "B.SilkS")
			(hide yes)
			(effects
				(font
					(size 1.27 1.27)
				)
				(justify mirror)
			)
		)
		(property "Value" "0R2J-2-GP"
			(at -0.064008 -3.993896 180)
			(unlocked yes)
			(layer "B.Fab")
			(hide yes)
			(effects
				(font
					(size 1.016 1.016)
					(thickness 0.1524)
				)
				(justify mirror)
			)
		)
		(property "Device Type" "R402H16"
			(at -0.064008 -5.517896 180)
			(unlocked yes)
			(layer "B.Fab")
			(hide yes)
			(effects
				(font
					(size 1.016 1.016)
					(thickness 0.1524)
				)
				(justify mirror)
			)
		)
		(duplicate_pad_numbers_are_jumpers no)
		(fp_line
			(start 0.508 -0.9398)
			(end 0.508 0.9398)
			(stroke
				(width 0.1524)
				(type default)
			)
			(layer "B.SilkS")
		)
		(fp_line
			(start -0.508 -0.9398)
			(end 0.508 -0.9398)
			(stroke
				(width 0.1524)
				(type default)
			)
			(layer "B.SilkS")
		)
		(fp_rect
			(start 0.508 0.9398)
			(end -0.508 -0.9398)
			(stroke
				(width 0)
				(type default)
			)
			(fill no)
			(layer "B.CrtYd")
		)
		(fp_rect
			(start 0.508 0.9398)
			(end -0.508 -0.9398)
			(stroke
				(width 0)
				(type default)
			)
			(fill no)
			(layer "B.Fab")
		)
		(pad "1" smd custom
			(at 0 -0.4445)
			(size 0.1397 0.1397)
			(layers "B.Cu" "B.Mask" "B.Paste")
			(net "REDV_RX8_N")
			(options
				(clearance outline)
				(anchor circle)
			)
			(primitives
				(gr_poly
					(pts
						(arc
							(start -0.1778 0.2794)
							(mid -0.249642 0.249642)
							(end -0.2794 0.1778)
						)
						(arc
							(start -0.2794 -0.1778)
							(mid -0.249642 -0.249642)
							(end -0.1778 -0.2794)
						)
						(arc
							(start 0.1778 -0.2794)
							(mid 0.249642 -0.249642)
							(end 0.2794 -0.1778)
						)
						(arc
							(start 0.2794 0.1778)
							(mid 0.249642 0.249642)
							(end 0.1778 0.2794)
						)
					)
					(width 0)
					(fill yes)
				)
			)
		)
		(pad "2" smd custom
			(at 0 0.4445)
			(size 0.1397 0.1397)
			(layers "B.Cu" "B.Mask" "B.Paste")
			(net "SAS_HDD_CONN_RX8_N")
			(options
				(clearance outline)
				(anchor circle)
			)
			(primitives
				(gr_poly
					(pts
						(arc
							(start -0.1778 0.2794)
							(mid -0.249642 0.249642)
							(end -0.2794 0.1778)
						)
						(arc
							(start -0.2794 -0.1778)
							(mid -0.249642 -0.249642)
							(end -0.1778 -0.2794)
						)
						(arc
							(start 0.1778 -0.2794)
							(mid 0.249642 -0.249642)
							(end 0.2794 -0.1778)
						)
						(arc
							(start 0.2794 0.1778)
							(mid 0.249642 0.249642)
							(end 0.1778 0.2794)
						)
					)
					(width 0)
					(fill yes)
				)
			)
		)
	)
	(footprint ""
		(layer "B.Cu")
		(at 144.399 -45.847)
		(property "Reference" "STP118"
			(at 0 0 0)
			(layer "B.SilkS")
			(hide yes)
			(effects
				(font
					(size 1.27 1.27)
				)
				(justify mirror)
			)
		)
		(property "Value" "TPAD28"
			(at -0.0127 -1.8034 0)
			(unlocked yes)
			(layer "B.Fab")
			(hide yes)
			(effects
				(font
					(size 1.016 1.016)
					(thickness 0.1524)
				)
				(justify mirror)
			)
		)
		(property "Device Type" "TPAD28"
			(at -0.0127 -3.3274 0)
			(unlocked yes)
			(layer "B.Fab")
			(hide yes)
			(effects
				(font
					(size 1.016 1.016)
					(thickness 0.1524)
				)
				(justify mirror)
			)
		)
		(duplicate_pad_numbers_are_jumpers no)
		(fp_poly
			(pts
				(arc
					(start 0.3556 0)
					(mid -0.3556 0)
					(end 0.3556 0)
				)
			)
			(stroke
				(width 0)
				(type default)
			)
			(fill no)
			(layer "B.CrtYd")
		)
		(fp_poly
			(pts
				(arc
					(start 0.6096 0)
					(mid -0.6096 0)
					(end 0.6096 0)
				)
			)
			(stroke
				(width 0)
				(type default)
			)
			(fill no)
			(layer "B.Fab")
		)
		(pad "1" smd circle
			(at 0 0 180)
			(size 0.7112 0.7112)
			(layers "B.Cu" "B.Mask" "B.Paste")
			(net "XM_ADDR_18")
		)
	)
	(footprint ""
		(layer "B.Cu")
		(at 114.281966 -45.72 -90)
		(property "Reference" "SR625"
			(at 0 0 90)
			(layer "B.SilkS")
			(hide yes)
			(effects
				(font
					(size 1.27 1.27)
				)
				(justify mirror)
			)
		)
		(property "Value" "2K2R2F-GP"
			(at -0.064008 -3.993896 270)
			(unlocked yes)
			(layer "B.Fab")
			(hide yes)
			(effects
				(font
					(size 1.016 1.016)
					(thickness 0.1524)
				)
				(justify mirror)
			)
		)
		(property "Device Type" "R402H16"
			(at -0.064008 -5.517896 270)
			(unlocked yes)
			(layer "B.Fab")
			(hide yes)
			(effects
				(font
					(size 1.016 1.016)
					(thickness 0.1524)
				)
				(justify mirror)
			)
		)
		(duplicate_pad_numbers_are_jumpers no)
		(fp_line
			(start -0.508 -0.9398)
			(end 0.508 -0.9398)
			(stroke
				(width 0.1524)
				(type default)
			)
			(layer "B.SilkS")
		)
		(fp_line
			(start 0.508 -0.9398)
			(end 0.508 0.9398)
			(stroke
				(width 0.1524)
				(type default)
			)
			(layer "B.SilkS")
		)
		(fp_rect
			(start 0.508 0.9398)
			(end -0.508 -0.9398)
			(stroke
				(width 0)
				(type default)
			)
			(fill no)
			(layer "B.CrtYd")
		)
		(fp_rect
			(start 0.508 0.9398)
			(end -0.508 -0.9398)
			(stroke
				(width 0)
				(type default)
			)
			(fill no)
			(layer "B.Fab")
		)
		(pad "1" smd custom
			(at 0 -0.4445 90)
			(size 0.1397 0.1397)
			(layers "B.Cu" "B.Mask" "B.Paste")
			(net "P1V8_C")
			(options
				(clearance outline)
				(anchor circle)
			)
			(primitives
				(gr_poly
					(pts
						(arc
							(start -0.1778 0.2794)
							(mid -0.249642 0.249642)
							(end -0.2794 0.1778)
						)
						(arc
							(start -0.2794 -0.1778)
							(mid -0.249642 -0.249642)
							(end -0.1778 -0.2794)
						)
						(arc
							(start 0.1778 -0.2794)
							(mid 0.249642 -0.249642)
							(end 0.2794 -0.1778)
						)
						(arc
							(start 0.2794 0.1778)
							(mid 0.249642 0.249642)
							(end 0.1778 0.2794)
						)
					)
					(width 0)
					(fill yes)
				)
			)
		)
		(pad "2" smd custom
			(at 0 0.4445 90)
			(size 0.1397 0.1397)
			(layers "B.Cu" "B.Mask" "B.Paste")
			(net "IOC_SDA_4")
			(options
				(clearance outline)
				(anchor circle)
			)
			(primitives
				(gr_poly
					(pts
						(arc
							(start -0.1778 0.2794)
							(mid -0.249642 0.249642)
							(end -0.2794 0.1778)
						)
						(arc
							(start -0.2794 -0.1778)
							(mid -0.249642 -0.249642)
							(end -0.1778 -0.2794)
						)
						(arc
							(start 0.1778 -0.2794)
							(mid 0.249642 -0.249642)
							(end 0.2794 -0.1778)
						)
						(arc
							(start 0.2794 0.1778)
							(mid 0.249642 0.249642)
							(end 0.1778 0.2794)
						)
					)
					(width 0)
					(fill yes)
				)
			)
		)
	)
	(footprint ""
		(layer "B.Cu")
		(at 32.462216 -232.33888)
		(property "Reference" "R509"
			(at 0 0 0)
			(layer "B.SilkS")
			(hide yes)
			(effects
				(font
					(size 1.27 1.27)
				)
				(justify mirror)
			)
		)
		(property "Value" "0R2J-2-GP"
			(at -0.064008 -3.993896 0)
			(unlocked yes)
			(layer "B.Fab")
			(hide yes)
			(effects
				(font
					(size 1.016 1.016)
					(thickness 0.1524)
				)
				(justify mirror)
			)
		)
		(property "Device Type" "R402H16"
			(at -0.064008 -5.517896 0)
			(unlocked yes)
			(layer "B.Fab")
			(hide yes)
			(effects
				(font
					(size 1.016 1.016)
					(thickness 0.1524)
				)
				(justify mirror)
			)
		)
		(duplicate_pad_numbers_are_jumpers no)
		(fp_line
			(start -0.508 -0.9398)
			(end 0.508 -0.9398)
			(stroke
				(width 0.1524)
				(type default)
			)
			(layer "B.SilkS")
		)
		(fp_line
			(start 0.508 -0.9398)
			(end 0.508 0.9398)
			(stroke
				(width 0.1524)
				(type default)
			)
			(layer "B.SilkS")
		)
		(fp_rect
			(start 0.508 0.9398)
			(end -0.508 -0.9398)
			(stroke
				(width 0)
				(type default)
			)
			(fill no)
			(layer "B.CrtYd")
		)
		(fp_rect
			(start 0.508 0.9398)
			(end -0.508 -0.9398)
			(stroke
				(width 0)
				(type default)
			)
			(fill no)
			(layer "B.Fab")
		)
		(pad "1" smd custom
			(at 0 -0.4445 180)
			(size 0.1397 0.1397)
			(layers "B.Cu" "B.Mask" "B.Paste")
			(net "SAS_HDD_PWR7_PCIE")
			(options
				(clearance outline)
				(anchor circle)
			)
			(primitives
				(gr_poly
					(pts
						(arc
							(start -0.1778 0.2794)
							(mid -0.249642 0.249642)
							(end -0.2794 0.1778)
						)
						(arc
							(start -0.2794 -0.1778)
							(mid -0.249642 -0.249642)
							(end -0.1778 -0.2794)
						)
						(arc
							(start 0.1778 -0.2794)
							(mid 0.249642 -0.249642)
							(end 0.2794 -0.1778)
						)
						(arc
							(start 0.2794 0.1778)
							(mid 0.249642 0.249642)
							(end 0.1778 0.2794)
						)
					)
					(width 0)
					(fill yes)
				)
			)
		)
		(pad "2" smd custom
			(at 0 0.4445 180)
			(size 0.1397 0.1397)
			(layers "B.Cu" "B.Mask" "B.Paste")
			(net "SAS_HDD_PWR7")
			(options
				(clearance outline)
				(anchor circle)
			)
			(primitives
				(gr_poly
					(pts
						(arc
							(start -0.1778 0.2794)
							(mid -0.249642 0.249642)
							(end -0.2794 0.1778)
						)
						(arc
							(start -0.2794 -0.1778)
							(mid -0.249642 -0.249642)
							(end -0.1778 -0.2794)
						)
						(arc
							(start 0.1778 -0.2794)
							(mid 0.249642 -0.249642)
							(end 0.2794 -0.1778)
						)
						(arc
							(start 0.2794 0.1778)
							(mid 0.249642 0.249642)
							(end 0.1778 0.2794)
						)
					)
					(width 0)
					(fill yes)
				)
			)
		)
	)
	(footprint ""
		(layer "B.Cu")
		(at 116.186966 -29.972 90)
		(property "Reference" "SC972"
			(at 0 0 90)
			(layer "B.SilkS")
			(hide yes)
			(effects
				(font
					(size 1.27 1.27)
				)
				(justify mirror)
			)
		)
		(property "Value" "SC1U10V2KX-4-GP"
			(at -1.1811 -2.7051 90)
			(unlocked yes)
			(layer "B.Fab")
			(hide yes)
			(effects
				(font
					(size 1.016 1.016)
					(thickness 0.1524)
				)
				(justify mirror)
			)
		)
		(property "Device Type" "C402H22"
			(at -1.1811 -4.2291 90)
			(unlocked yes)
			(layer "B.Fab")
			(hide yes)
			(effects
				(font
					(size 1.016 1.016)
					(thickness 0.1524)
				)
				(justify mirror)
			)
		)
		(duplicate_pad_numbers_are_jumpers no)
		(fp_rect
			(start 0.4318 0.9525)
			(end -0.4318 -0.9525)
			(stroke
				(width 0)
				(type default)
			)
			(fill no)
			(layer "B.CrtYd")
		)
		(fp_rect
			(start 0.4318 0.9525)
			(end -0.4318 -0.9525)
			(stroke
				(width 0)
				(type default)
			)
			(fill no)
			(layer "B.Fab")
		)
		(pad "1" smd custom
			(at 0 -0.4445 270)
			(size 0.1524 0.1524)
			(layers "B.Cu" "B.Mask" "B.Paste")
			(net "P1V8_C")
			(options
				(clearance outline)
				(anchor circle)
			)
			(primitives
				(gr_poly
					(pts
						(arc
							(start 0.3048 0.2032)
							(mid 0.275042 0.275042)
							(end 0.2032 0.3048)
						)
						(arc
							(start -0.2032 0.3048)
							(mid -0.275042 0.275042)
							(end -0.3048 0.2032)
						)
						(arc
							(start -0.3048 -0.2032)
							(mid -0.275042 -0.275042)
							(end -0.2032 -0.3048)
						)
						(arc
							(start 0.2032 -0.3048)
							(mid 0.275042 -0.275042)
							(end 0.3048 -0.2032)
						)
					)
					(width 0)
					(fill yes)
				)
			)
		)
		(pad "2" smd custom
			(at 0 0.4445 270)
			(size 0.1524 0.1524)
			(layers "B.Cu" "B.Mask" "B.Paste")
			(net "GND")
			(options
				(clearance outline)
				(anchor circle)
			)
			(primitives
				(gr_poly
					(pts
						(arc
							(start 0.3048 0.2032)
							(mid 0.275042 0.275042)
							(end 0.2032 0.3048)
						)
						(arc
							(start -0.2032 0.3048)
							(mid -0.275042 0.275042)
							(end -0.3048 0.2032)
						)
						(arc
							(start -0.3048 -0.2032)
							(mid -0.275042 -0.275042)
							(end -0.2032 -0.3048)
						)
						(arc
							(start 0.2032 -0.3048)
							(mid 0.275042 -0.275042)
							(end 0.3048 -0.2032)
						)
					)
					(width 0)
					(fill yes)
				)
			)
		)
	)
	(footprint ""
		(layer "B.Cu")
		(at 188.949584 -89.799922)
		(property "Reference" ""
			(at 0 0 0)
			(layer "B.SilkS")
			(hide yes)
			(effects
				(font
					(size 1.27 1.27)
				)
				(justify mirror)
			)
		)
		(property "Value" "*"
			(at 5.5753 -0.4572 0)
			(unlocked yes)
			(layer "B.Fab")
			(hide yes)
			(effects
				(font
					(size 1.016 1.016)
					(thickness 0.1524)
				)
				(justify mirror)
			)
		)
		(duplicate_pad_numbers_are_jumpers no)
		(fp_poly
			(pts
				(arc
					(start 4.3053 0)
					(mid -4.3053 0)
					(end 4.3053 0)
				)
			)
			(stroke
				(width 0)
				(type default)
			)
			(fill no)
			(layer "B.CrtYd")
		)
		(fp_poly
			(pts
				(arc
					(start 4.3053 0)
					(mid -4.3053 0)
					(end 4.3053 0)
				)
			)
			(stroke
				(width 0)
				(type default)
			)
			(fill no)
			(layer "B.Fab")
		)
		(pad "1" smd custom
			(at 2.95275 0 180)
			(size 2.000013 2.000013)
			(layers "B.Cu" "B.Mask" "B.Paste")
			(net "Net_50")
			(options
				(clearance outline)
				(anchor circle)
			)
			(primitives
				(gr_poly
					(pts
						(arc
							(start 4.0005 -0.00254)
							(mid -4.000501 0)
							(end 4.0005 0.00254)
						)
						(arc
							(start 1.905 0.00254)
							(mid -1.905002 0)
							(end 1.905 -0.00254)
						)
					)
					(width 0)
					(fill yes)
				)
			)
		)
	)
	(footprint ""
		(layer "B.Cu")
		(at 98.56216 -31.623)
		(property "Reference" "SC868"
			(at 0 0 0)
			(layer "B.SilkS")
			(hide yes)
			(effects
				(font
					(size 1.27 1.27)
				)
				(justify mirror)
			)
		)
		(property "Value" "SCD22U6D3V1MX-1-GP"
			(at 2.8321 -1.7399 0)
			(unlocked yes)
			(layer "B.Fab")
			(hide yes)
			(effects
				(font
					(size 1.016 1.016)
					(thickness 0.1524)
				)
				(justify mirror)
			)
		)
		(property "Device Type" "C0201H13"
			(at 2.8321 -3.2639 0)
			(unlocked yes)
			(layer "B.Fab")
			(hide yes)
			(effects
				(font
					(size 1.016 1.016)
					(thickness 0.1524)
				)
				(justify mirror)
			)
		)
		(duplicate_pad_numbers_are_jumpers no)
		(fp_rect
			(start 0.2794 0.6477)
			(end -0.2794 -0.6477)
			(stroke
				(width 0)
				(type default)
			)
			(fill no)
			(layer "B.CrtYd")
		)
		(fp_rect
			(start 0.2794 0.6477)
			(end -0.2794 -0.6477)
			(stroke
				(width 0)
				(type default)
			)
			(fill no)
			(layer "B.Fab")
		)
		(pad "1" smd custom
			(at 0 -0.2794 180)
			(size 0.0762 0.0762)
			(layers "B.Cu" "B.Mask" "B.Paste")
			(net "PCIE_SAS_C_CPU_RX_N3")
			(options
				(clearance outline)
				(anchor circle)
			)
			(primitives
				(gr_poly
					(pts
						(arc
							(start 0.1524 0.127)
							(mid 0.137521 0.162921)
							(end 0.1016 0.1778)
						)
						(arc
							(start -0.1016 0.1778)
							(mid -0.137521 0.162921)
							(end -0.1524 0.127)
						)
						(arc
							(start -0.1524 -0.127)
							(mid -0.137521 -0.162921)
							(end -0.1016 -0.1778)
						)
						(arc
							(start 0.1016 -0.1778)
							(mid 0.137521 -0.162921)
							(end 0.1524 -0.127)
						)
					)
					(width 0)
					(fill yes)
				)
			)
		)
		(pad "2" smd custom
			(at 0 0.2794 180)
			(size 0.0762 0.0762)
			(layers "B.Cu" "B.Mask" "B.Paste")
			(net "PCIE_SAS_CPU_RX_N3")
			(options
				(clearance outline)
				(anchor circle)
			)
			(primitives
				(gr_poly
					(pts
						(arc
							(start 0.1524 0.127)
							(mid 0.137521 0.162921)
							(end 0.1016 0.1778)
						)
						(arc
							(start -0.1016 0.1778)
							(mid -0.137521 0.162921)
							(end -0.1524 0.127)
						)
						(arc
							(start -0.1524 -0.127)
							(mid -0.137521 -0.162921)
							(end -0.1016 -0.1778)
						)
						(arc
							(start 0.1016 -0.1778)
							(mid 0.137521 -0.162921)
							(end 0.1524 -0.127)
						)
					)
					(width 0)
					(fill yes)
				)
			)
		)
	)
)
